(kicad_pcb
	(version 20260206)
	(generator "pcbnew")
	(generator_version "10.0")
	(general
		(thickness 1.6)
		(legacy_teardrops no)
	)
	(paper "A4")
	(title_block
		(title "03242023_DA0F0TMBIJ0_F0T_Motherboard_J_brd_V01_OCP.brd")
		(comment 1 "Grand Teton / footprints 1336-1341 of 6105")
	)
	(layers
		(0 "F.Cu" signal "TOP")
		(4 "In1.Cu" signal "GND")
		(6 "In2.Cu" signal "IN1")
		(8 "In3.Cu" signal "GND1")
		(10 "In4.Cu" signal "IN2")
		(12 "In5.Cu" signal "GND2")
		(14 "In6.Cu" signal "IN3")
		(16 "In7.Cu" signal "GND3")
		(18 "In8.Cu" signal "VCC")
		(20 "In9.Cu" signal "VCC1")
		(22 "In10.Cu" signal "GND4")
		(24 "In11.Cu" signal "IN4")
		(26 "In12.Cu" signal "GND5")
		(28 "In13.Cu" signal "IN5")
		(30 "In14.Cu" signal "GND6")
		(32 "In15.Cu" signal "IN6")
		(34 "In16.Cu" signal "GND7")
		(2 "B.Cu" signal "BOTTOM")
		(9 "F.Adhes" user "F.Adhesive")
		(11 "B.Adhes" user "B.Adhesive")
		(13 "F.Paste" user "Package Geometry/Pastemask Top")
		(15 "B.Paste" user "Package Geometry/Pastemask Bottom")
		(5 "F.SilkS" user "Ref Des/Silkscreen Top")
		(7 "B.SilkS" user "Ref Des/Silkscreen Bottom")
		(1 "F.Mask" user "Board Geometry/Soldermask Top")
		(3 "B.Mask" user "Board Geometry/Soldermask Bottom")
		(17 "Dwgs.User" user "User.Drawings")
		(19 "Cmts.User" user "User.Comments")
		(21 "Eco1.User" user "User.Eco1")
		(23 "Eco2.User" user "User.Eco2")
		(25 "Edge.Cuts" user "Board Geometry/Outline")
		(27 "Margin" user)
		(31 "F.CrtYd" user "Package Geometry/Place Bound Top")
		(29 "B.CrtYd" user "Package Geometry/Place Bound Bottom")
		(35 "F.Fab" user "Ref Des/Assembly Top")
		(33 "B.Fab" user "Ref Des/Assembly Bottom")
	)
	(footprint ""
		(layer "F.Cu")
		(at 348.606364 -358.906826)
		(property "Reference" "R2375"
			(at 0 0 0)
			(layer "F.SilkS")
			(hide yes)
			(effects
				(font
					(size 1.27 1.27)
				)
			)
		)
		(property "Value" ""
			(at 0 0 0)
			(layer "F.Fab")
			(effects
				(font
					(size 1.27 1.27)
				)
			)
		)
		(duplicate_pad_numbers_are_jumpers no)
		(fp_line
			(start -0.7874 -0.4064)
			(end 0.7874 -0.4064)
			(stroke
				(width 0.1524)
				(type default)
			)
			(layer "F.SilkS")
		)
		(fp_line
			(start -0.7874 0.4064)
			(end -0.7874 -0.4064)
			(stroke
				(width 0.1524)
				(type default)
			)
			(layer "F.SilkS")
		)
		(fp_line
			(start 0.7874 -0.4064)
			(end 0.7874 0.4064)
			(stroke
				(width 0.1524)
				(type default)
			)
			(layer "F.SilkS")
		)
		(fp_line
			(start 0.7874 0.4064)
			(end -0.7874 0.4064)
			(stroke
				(width 0.1524)
				(type default)
			)
			(layer "F.SilkS")
		)
		(fp_line
			(start -0.67945 -0.305054)
			(end -0.12065 -0.305054)
			(stroke
				(width 0.1)
				(type default)
			)
			(layer "F.Fab")
		)
		(fp_line
			(start -0.67945 0.3048)
			(end -0.67945 -0.305054)
			(stroke
				(width 0.1)
				(type default)
			)
			(layer "F.Fab")
		)
		(fp_line
			(start -0.12065 -0.305054)
			(end -0.12065 -0.2794)
			(stroke
				(width 0.1)
				(type default)
			)
			(layer "F.Fab")
		)
		(fp_line
			(start -0.12065 -0.2794)
			(end 0.12065 -0.2794)
			(stroke
				(width 0.1)
				(type default)
			)
			(layer "F.Fab")
		)
		(fp_line
			(start -0.12065 0.2794)
			(end -0.12065 0.3048)
			(stroke
				(width 0.1)
				(type default)
			)
			(layer "F.Fab")
		)
		(fp_line
			(start -0.12065 0.3048)
			(end -0.67945 0.3048)
			(stroke
				(width 0.1)
				(type default)
			)
			(layer "F.Fab")
		)
		(fp_line
			(start 0.120396 0.2794)
			(end -0.12065 0.2794)
			(stroke
				(width 0.1)
				(type default)
			)
			(layer "F.Fab")
		)
		(fp_line
			(start 0.120396 0.3048)
			(end 0.120396 0.2794)
			(stroke
				(width 0.1)
				(type default)
			)
			(layer "F.Fab")
		)
		(fp_line
			(start 0.12065 -0.3048)
			(end 0.67945 -0.3048)
			(stroke
				(width 0.1)
				(type default)
			)
			(layer "F.Fab")
		)
		(fp_line
			(start 0.12065 -0.2794)
			(end 0.12065 -0.3048)
			(stroke
				(width 0.1)
				(type default)
			)
			(layer "F.Fab")
		)
		(fp_line
			(start 0.67945 -0.3048)
			(end 0.67945 0.3048)
			(stroke
				(width 0.1)
				(type default)
			)
			(layer "F.Fab")
		)
		(fp_line
			(start 0.67945 0.3048)
			(end 0.120396 0.3048)
			(stroke
				(width 0.1)
				(type default)
			)
			(layer "F.Fab")
		)
		(pad "1" smd circle
			(at -0.40005 0)
			(size 0 0)
			(layers "F.Cu" "F.Mask" "F.Paste")
			(net "P3V3_AUX")
		)
		(pad "2" smd circle
			(at 0.40005 0)
			(size 0 0)
			(layers "F.Cu" "F.Mask" "F.Paste")
			(net "PVCCIN_CPU0_PIN_ALERT")
		)
	)
	(footprint ""
		(layer "F.Cu")
		(at 107.019598 -15.91691)
		(property "Reference" "R3553"
			(at 0 0 0)
			(layer "F.SilkS")
			(hide yes)
			(effects
				(font
					(size 1.27 1.27)
				)
			)
		)
		(property "Value" ""
			(at 0 0 0)
			(layer "F.Fab")
			(effects
				(font
					(size 1.27 1.27)
				)
			)
		)
		(duplicate_pad_numbers_are_jumpers no)
		(fp_line
			(start -0.7874 -0.4064)
			(end 0.7874 -0.4064)
			(stroke
				(width 0.1524)
				(type default)
			)
			(layer "F.SilkS")
		)
		(fp_line
			(start -0.7874 0.4064)
			(end -0.7874 -0.4064)
			(stroke
				(width 0.1524)
				(type default)
			)
			(layer "F.SilkS")
		)
		(fp_line
			(start 0.7874 -0.4064)
			(end 0.7874 0.4064)
			(stroke
				(width 0.1524)
				(type default)
			)
			(layer "F.SilkS")
		)
		(fp_line
			(start 0.7874 0.4064)
			(end -0.7874 0.4064)
			(stroke
				(width 0.1524)
				(type default)
			)
			(layer "F.SilkS")
		)
		(fp_line
			(start -0.67945 -0.305054)
			(end -0.12065 -0.305054)
			(stroke
				(width 0.1)
				(type default)
			)
			(layer "F.Fab")
		)
		(fp_line
			(start -0.67945 0.3048)
			(end -0.67945 -0.305054)
			(stroke
				(width 0.1)
				(type default)
			)
			(layer "F.Fab")
		)
		(fp_line
			(start -0.12065 -0.305054)
			(end -0.12065 -0.2794)
			(stroke
				(width 0.1)
				(type default)
			)
			(layer "F.Fab")
		)
		(fp_line
			(start -0.12065 -0.2794)
			(end 0.12065 -0.2794)
			(stroke
				(width 0.1)
				(type default)
			)
			(layer "F.Fab")
		)
		(fp_line
			(start -0.12065 0.2794)
			(end -0.12065 0.3048)
			(stroke
				(width 0.1)
				(type default)
			)
			(layer "F.Fab")
		)
		(fp_line
			(start -0.12065 0.3048)
			(end -0.67945 0.3048)
			(stroke
				(width 0.1)
				(type default)
			)
			(layer "F.Fab")
		)
		(fp_line
			(start 0.120396 0.2794)
			(end -0.12065 0.2794)
			(stroke
				(width 0.1)
				(type default)
			)
			(layer "F.Fab")
		)
		(fp_line
			(start 0.120396 0.3048)
			(end 0.120396 0.2794)
			(stroke
				(width 0.1)
				(type default)
			)
			(layer "F.Fab")
		)
		(fp_line
			(start 0.12065 -0.3048)
			(end 0.67945 -0.3048)
			(stroke
				(width 0.1)
				(type default)
			)
			(layer "F.Fab")
		)
		(fp_line
			(start 0.12065 -0.2794)
			(end 0.12065 -0.3048)
			(stroke
				(width 0.1)
				(type default)
			)
			(layer "F.Fab")
		)
		(fp_line
			(start 0.67945 -0.3048)
			(end 0.67945 0.3048)
			(stroke
				(width 0.1)
				(type default)
			)
			(layer "F.Fab")
		)
		(fp_line
			(start 0.67945 0.3048)
			(end 0.120396 0.3048)
			(stroke
				(width 0.1)
				(type default)
			)
			(layer "F.Fab")
		)
		(pad "1" smd circle
			(at -0.40005 0)
			(size 0 0)
			(layers "F.Cu" "F.Mask" "F.Paste")
			(net "SMB_LM75_3_3V3AUX_SCL")
		)
		(pad "2" smd circle
			(at 0.40005 0)
			(size 0 0)
			(layers "F.Cu" "F.Mask" "F.Paste")
			(net "SMB_LM75_3_3V3AUX_SCL_R1")
		)
	)
	(footprint ""
		(layer "F.Cu")
		(at 118.542816 -260.36524 -90)
		(property "Reference" "C442"
			(at 0 0 270)
			(layer "F.SilkS")
			(hide yes)
			(effects
				(font
					(size 1.27 1.27)
				)
			)
		)
		(property "Value" ""
			(at 0 0 270)
			(layer "F.Fab")
			(effects
				(font
					(size 1.27 1.27)
				)
			)
		)
		(duplicate_pad_numbers_are_jumpers no)
		(fp_line
			(start -0.7874 0.4064)
			(end -0.7874 -0.4064)
			(stroke
				(width 0.1524)
				(type default)
			)
			(layer "F.SilkS")
		)
		(fp_line
			(start 0.7874 0.4064)
			(end -0.7874 0.4064)
			(stroke
				(width 0.1524)
				(type default)
			)
			(layer "F.SilkS")
		)
		(fp_line
			(start -0.7874 -0.4064)
			(end 0.7874 -0.4064)
			(stroke
				(width 0.1524)
				(type default)
			)
			(layer "F.SilkS")
		)
		(fp_line
			(start 0.7874 -0.4064)
			(end 0.7874 0.4064)
			(stroke
				(width 0.1524)
				(type default)
			)
			(layer "F.SilkS")
		)
		(fp_line
			(start -0.67945 0.3048)
			(end -0.67945 -0.305054)
			(stroke
				(width 0.1)
				(type default)
			)
			(layer "F.Fab")
		)
		(fp_line
			(start -0.12065 0.3048)
			(end -0.67945 0.3048)
			(stroke
				(width 0.1)
				(type default)
			)
			(layer "F.Fab")
		)
		(fp_line
			(start 0.120396 0.3048)
			(end 0.120396 0.2794)
			(stroke
				(width 0.1)
				(type default)
			)
			(layer "F.Fab")
		)
		(fp_line
			(start 0.67945 0.3048)
			(end 0.120396 0.3048)
			(stroke
				(width 0.1)
				(type default)
			)
			(layer "F.Fab")
		)
		(fp_line
			(start -0.12065 0.2794)
			(end -0.12065 0.3048)
			(stroke
				(width 0.1)
				(type default)
			)
			(layer "F.Fab")
		)
		(fp_line
			(start 0.120396 0.2794)
			(end -0.12065 0.2794)
			(stroke
				(width 0.1)
				(type default)
			)
			(layer "F.Fab")
		)
		(fp_line
			(start -0.12065 -0.2794)
			(end 0.12065 -0.2794)
			(stroke
				(width 0.1)
				(type default)
			)
			(layer "F.Fab")
		)
		(fp_line
			(start 0.12065 -0.2794)
			(end 0.12065 -0.3048)
			(stroke
				(width 0.1)
				(type default)
			)
			(layer "F.Fab")
		)
		(fp_line
			(start 0.12065 -0.3048)
			(end 0.67945 -0.3048)
			(stroke
				(width 0.1)
				(type default)
			)
			(layer "F.Fab")
		)
		(fp_line
			(start 0.67945 -0.3048)
			(end 0.67945 0.3048)
			(stroke
				(width 0.1)
				(type default)
			)
			(layer "F.Fab")
		)
		(fp_line
			(start -0.67945 -0.305054)
			(end -0.12065 -0.305054)
			(stroke
				(width 0.1)
				(type default)
			)
			(layer "F.Fab")
		)
		(fp_line
			(start -0.12065 -0.305054)
			(end -0.12065 -0.2794)
			(stroke
				(width 0.1)
				(type default)
			)
			(layer "F.Fab")
		)
		(pad "1" smd circle
			(at -0.40005 0 270)
			(size 0 0)
			(layers "F.Cu" "F.Mask" "F.Paste")
			(net "PVCCFA_EHV_FIVRA_CPU1")
		)
		(pad "2" smd circle
			(at 0.40005 0 270)
			(size 0 0)
			(layers "F.Cu" "F.Mask" "F.Paste")
			(net "GND")
		)
	)
	(footprint ""
		(layer "F.Cu")
		(at 180.074062 -32.935672 -90)
		(property "Reference" "R3998"
			(at 0 0 270)
			(layer "F.SilkS")
			(hide yes)
			(effects
				(font
					(size 1.27 1.27)
				)
			)
		)
		(property "Value" ""
			(at 0 0 270)
			(layer "F.Fab")
			(effects
				(font
					(size 1.27 1.27)
				)
			)
		)
		(duplicate_pad_numbers_are_jumpers no)
		(fp_line
			(start -0.7874 0.4064)
			(end -0.7874 -0.4064)
			(stroke
				(width 0.1524)
				(type default)
			)
			(layer "F.SilkS")
		)
		(fp_line
			(start 0.7874 0.4064)
			(end -0.7874 0.4064)
			(stroke
				(width 0.1524)
				(type default)
			)
			(layer "F.SilkS")
		)
		(fp_line
			(start -0.7874 -0.4064)
			(end 0.7874 -0.4064)
			(stroke
				(width 0.1524)
				(type default)
			)
			(layer "F.SilkS")
		)
		(fp_line
			(start 0.7874 -0.4064)
			(end 0.7874 0.4064)
			(stroke
				(width 0.1524)
				(type default)
			)
			(layer "F.SilkS")
		)
		(fp_line
			(start -0.67945 0.3048)
			(end -0.67945 -0.305054)
			(stroke
				(width 0.1)
				(type default)
			)
			(layer "F.Fab")
		)
		(fp_line
			(start -0.12065 0.3048)
			(end -0.67945 0.3048)
			(stroke
				(width 0.1)
				(type default)
			)
			(layer "F.Fab")
		)
		(fp_line
			(start 0.120396 0.3048)
			(end 0.120396 0.2794)
			(stroke
				(width 0.1)
				(type default)
			)
			(layer "F.Fab")
		)
		(fp_line
			(start 0.67945 0.3048)
			(end 0.120396 0.3048)
			(stroke
				(width 0.1)
				(type default)
			)
			(layer "F.Fab")
		)
		(fp_line
			(start -0.12065 0.2794)
			(end -0.12065 0.3048)
			(stroke
				(width 0.1)
				(type default)
			)
			(layer "F.Fab")
		)
		(fp_line
			(start 0.120396 0.2794)
			(end -0.12065 0.2794)
			(stroke
				(width 0.1)
				(type default)
			)
			(layer "F.Fab")
		)
		(fp_line
			(start -0.12065 -0.2794)
			(end 0.12065 -0.2794)
			(stroke
				(width 0.1)
				(type default)
			)
			(layer "F.Fab")
		)
		(fp_line
			(start 0.12065 -0.2794)
			(end 0.12065 -0.3048)
			(stroke
				(width 0.1)
				(type default)
			)
			(layer "F.Fab")
		)
		(fp_line
			(start 0.12065 -0.3048)
			(end 0.67945 -0.3048)
			(stroke
				(width 0.1)
				(type default)
			)
			(layer "F.Fab")
		)
		(fp_line
			(start 0.67945 -0.3048)
			(end 0.67945 0.3048)
			(stroke
				(width 0.1)
				(type default)
			)
			(layer "F.Fab")
		)
		(fp_line
			(start -0.67945 -0.305054)
			(end -0.12065 -0.305054)
			(stroke
				(width 0.1)
				(type default)
			)
			(layer "F.Fab")
		)
		(fp_line
			(start -0.12065 -0.305054)
			(end -0.12065 -0.2794)
			(stroke
				(width 0.1)
				(type default)
			)
			(layer "F.Fab")
		)
		(pad "1" smd circle
			(at -0.40005 0 270)
			(size 0 0)
			(layers "F.Cu" "F.Mask" "F.Paste")
			(net "P12V_SCM_EN")
		)
		(pad "2" smd circle
			(at 0.40005 0 270)
			(size 0 0)
			(layers "F.Cu" "F.Mask" "F.Paste")
			(net "P12V_SCM_EN_R2")
		)
	)
	(footprint ""
		(layer "F.Cu")
		(at 348.404942 -355.359462 180)
		(property "Reference" "R2382"
			(at 0 0 180)
			(layer "F.SilkS")
			(hide yes)
			(effects
				(font
					(size 1.27 1.27)
				)
			)
		)
		(property "Value" ""
			(at 0 0 180)
			(layer "F.Fab")
			(effects
				(font
					(size 1.27 1.27)
				)
			)
		)
		(duplicate_pad_numbers_are_jumpers no)
		(fp_line
			(start 0.7874 0.4064)
			(end -0.7874 0.4064)
			(stroke
				(width 0.1524)
				(type default)
			)
			(layer "F.SilkS")
		)
		(fp_line
			(start 0.7874 -0.4064)
			(end 0.7874 0.4064)
			(stroke
				(width 0.1524)
				(type default)
			)
			(layer "F.SilkS")
		)
		(fp_line
			(start -0.7874 0.4064)
			(end -0.7874 -0.4064)
			(stroke
				(width 0.1524)
				(type default)
			)
			(layer "F.SilkS")
		)
		(fp_line
			(start -0.7874 -0.4064)
			(end 0.7874 -0.4064)
			(stroke
				(width 0.1524)
				(type default)
			)
			(layer "F.SilkS")
		)
		(fp_line
			(start 0.67945 0.3048)
			(end 0.120396 0.3048)
			(stroke
				(width 0.1)
				(type default)
			)
			(layer "F.Fab")
		)
		(fp_line
			(start 0.67945 -0.3048)
			(end 0.67945 0.3048)
			(stroke
				(width 0.1)
				(type default)
			)
			(layer "F.Fab")
		)
		(fp_line
			(start 0.12065 -0.2794)
			(end 0.12065 -0.3048)
			(stroke
				(width 0.1)
				(type default)
			)
			(layer "F.Fab")
		)
		(fp_line
			(start 0.12065 -0.3048)
			(end 0.67945 -0.3048)
			(stroke
				(width 0.1)
				(type default)
			)
			(layer "F.Fab")
		)
		(fp_line
			(start 0.120396 0.3048)
			(end 0.120396 0.2794)
			(stroke
				(width 0.1)
				(type default)
			)
			(layer "F.Fab")
		)
		(fp_line
			(start 0.120396 0.2794)
			(end -0.12065 0.2794)
			(stroke
				(width 0.1)
				(type default)
			)
			(layer "F.Fab")
		)
		(fp_line
			(start -0.12065 0.3048)
			(end -0.67945 0.3048)
			(stroke
				(width 0.1)
				(type default)
			)
			(layer "F.Fab")
		)
		(fp_line
			(start -0.12065 0.2794)
			(end -0.12065 0.3048)
			(stroke
				(width 0.1)
				(type default)
			)
			(layer "F.Fab")
		)
		(fp_line
			(start -0.12065 -0.2794)
			(end 0.12065 -0.2794)
			(stroke
				(width 0.1)
				(type default)
			)
			(layer "F.Fab")
		)
		(fp_line
			(start -0.12065 -0.305054)
			(end -0.12065 -0.2794)
			(stroke
				(width 0.1)
				(type default)
			)
			(layer "F.Fab")
		)
		(fp_line
			(start -0.67945 0.3048)
			(end -0.67945 -0.305054)
			(stroke
				(width 0.1)
				(type default)
			)
			(layer "F.Fab")
		)
		(fp_line
			(start -0.67945 -0.305054)
			(end -0.12065 -0.305054)
			(stroke
				(width 0.1)
				(type default)
			)
			(layer "F.Fab")
		)
		(pad "1" smd circle
			(at -0.40005 0 180)
			(size 0 0)
			(layers "F.Cu" "F.Mask" "F.Paste")
			(net "SVID_ALERT0_CPU0_R_N")
		)
		(pad "2" smd circle
			(at 0.40005 0 180)
			(size 0 0)
			(layers "F.Cu" "F.Mask" "F.Paste")
			(net "PVNN_TERM_CPU0")
		)
	)
	(footprint ""
		(layer "F.Cu")
		(at 432.680618 -183.64327 180)
		(property "Reference" "PC2221"
			(at 0 0 180)
			(layer "F.SilkS")
			(hide yes)
			(effects
				(font
					(size 1.27 1.27)
				)
			)
		)
		(property "Value" ""
			(at 0 0 180)
			(layer "F.Fab")
			(effects
				(font
					(size 1.27 1.27)
				)
			)
		)
		(duplicate_pad_numbers_are_jumpers no)
		(fp_line
			(start 0.7874 0.4064)
			(end -0.7874 0.4064)
			(stroke
				(width 0.1524)
				(type default)
			)
			(layer "F.SilkS")
		)
		(fp_line
			(start 0.7874 -0.4064)
			(end 0.7874 0.4064)
			(stroke
				(width 0.1524)
				(type default)
			)
			(layer "F.SilkS")
		)
		(fp_line
			(start -0.7874 0.4064)
			(end -0.7874 -0.4064)
			(stroke
				(width 0.1524)
				(type default)
			)
			(layer "F.SilkS")
		)
		(fp_line
			(start -0.7874 -0.4064)
			(end 0.7874 -0.4064)
			(stroke
				(width 0.1524)
				(type default)
			)
			(layer "F.SilkS")
		)
		(fp_line
			(start 0.67945 0.3048)
			(end 0.120396 0.3048)
			(stroke
				(width 0.1)
				(type default)
			)
			(layer "F.Fab")
		)
		(fp_line
			(start 0.67945 -0.3048)
			(end 0.67945 0.3048)
			(stroke
				(width 0.1)
				(type default)
			)
			(layer "F.Fab")
		)
		(fp_line
			(start 0.12065 -0.2794)
			(end 0.12065 -0.3048)
			(stroke
				(width 0.1)
				(type default)
			)
			(layer "F.Fab")
		)
		(fp_line
			(start 0.12065 -0.3048)
			(end 0.67945 -0.3048)
			(stroke
				(width 0.1)
				(type default)
			)
			(layer "F.Fab")
		)
		(fp_line
			(start 0.120396 0.3048)
			(end 0.120396 0.2794)
			(stroke
				(width 0.1)
				(type default)
			)
			(layer "F.Fab")
		)
		(fp_line
			(start 0.120396 0.2794)
			(end -0.12065 0.2794)
			(stroke
				(width 0.1)
				(type default)
			)
			(layer "F.Fab")
		)
		(fp_line
			(start -0.12065 0.3048)
			(end -0.67945 0.3048)
			(stroke
				(width 0.1)
				(type default)
			)
			(layer "F.Fab")
		)
		(fp_line
			(start -0.12065 0.2794)
			(end -0.12065 0.3048)
			(stroke
				(width 0.1)
				(type default)
			)
			(layer "F.Fab")
		)
		(fp_line
			(start -0.12065 -0.2794)
			(end 0.12065 -0.2794)
			(stroke
				(width 0.1)
				(type default)
			)
			(layer "F.Fab")
		)
		(fp_line
			(start -0.12065 -0.305054)
			(end -0.12065 -0.2794)
			(stroke
				(width 0.1)
				(type default)
			)
			(layer "F.Fab")
		)
		(fp_line
			(start -0.67945 0.3048)
			(end -0.67945 -0.305054)
			(stroke
				(width 0.1)
				(type default)
			)
			(layer "F.Fab")
		)
		(fp_line
			(start -0.67945 -0.305054)
			(end -0.12065 -0.305054)
			(stroke
				(width 0.1)
				(type default)
			)
			(layer "F.Fab")
		)
		(pad "1" smd circle
			(at -0.40005 0 180)
			(size 0 0)
			(layers "F.Cu" "F.Mask" "F.Paste")
			(net "PVNN_MAIN_CPU0_VCC")
		)
		(pad "2" smd circle
			(at 0.40005 0 180)
			(size 0 0)
			(layers "F.Cu" "F.Mask" "F.Paste")
			(net "GND")
		)
	)
)
